(kicad_pcb
	(version 20241229)
	(generator "pcbnew")
	(generator_version "9.0")
	(general
		(thickness 1.6296)
		(legacy_teardrops no)
	)
	(paper "A3")
	(title_block
		(title "Thunderbolt to 10GbE adapter")
		(date "2026-04-21")
		(rev "1.1.0")
		(company "Antmicro Ltd")
		(comment 1 "www.antmicro.com")
		(comment 9 "footprint 288 of 703 (U14), pads 480-503 of 503")
	)
	(layers
		(0 "F.Cu" signal)
		(4 "In1.Cu" signal)
		(6 "In2.Cu" signal)
		(8 "In3.Cu" signal)
		(10 "In4.Cu" signal)
		(12 "In5.Cu" signal)
		(14 "In6.Cu" signal)
		(2 "B.Cu" signal)
		(9 "F.Adhes" user "F.Adhesive")
		(11 "B.Adhes" user "B.Adhesive")
		(13 "F.Paste" user)
		(15 "B.Paste" user)
		(5 "F.SilkS" user "F.Silkscreen")
		(7 "B.SilkS" user "B.Silkscreen")
		(1 "F.Mask" user)
		(3 "B.Mask" user)
		(17 "Dwgs.User" user "User.Drawings")
		(19 "Cmts.User" user "User.Comments")
		(21 "Eco1.User" user "User.Eco1")
		(23 "Eco2.User" user "User.Eco2")
		(25 "Edge.Cuts" user)
		(27 "Margin" user)
		(31 "F.CrtYd" user "F.Courtyard")
		(29 "B.CrtYd" user "B.Courtyard")
		(35 "F.Fab" user)
		(33 "B.Fab" user)
	)
	(footprint "antmicro-footprints:FCBGA-503_22x22mm_Layout21x24_P1mm"
		(layer "F.Cu")
		(at 151.005 81.499999 -90)
		(property "Reference" "U14"
			(at -11.499999 11.005 0)
			(layer "F.SilkS")
			(effects
				(font
					(size 0.7 0.7)
					(thickness 0.15)
				)
				(justify left bottom)
			)
		)
		(property "Value" "EZX710AT2_S_LMR5"
			(at -11.4 12.5 270)
			(layer "F.Fab")
			(effects
				(font
					(size 0.7 0.7)
					(thickness 0.15)
				)
				(justify left bottom)
			)
		)
		(property "Datasheet" "https://www.google.com/url?sa=t&source=web&rct=j&opi=89978449&url=https://cdrdv2-public.intel.com/596333/596333_X710-TM4_Datasheet_v_2_4.pdf&ved=2ahUKEwiSuv20_sCOAxXVCRAIHdxGO_UQFnoECBEQAQ&usg=AOvVaw1CjGyrGWE8ZvOdw4VBsY6U"
			(at 0 0 270)
			(layer "F.Fab")
			(effects
				(font
					(size 0.7 0.7)
					(thickness 0.15)
				)
				(justify left bottom)
			)
		)
		(property "Description" "Ethernet ICs Intel Ethernet Controller 10 Gigabit X7"
			(at 0 0 270)
			(layer "F.Fab")
			(effects
				(font
					(size 0.7 0.7)
					(thickness 0.15)
				)
				(justify left bottom)
			)
		)
		(property "MPN" "EZX710AT2 S LMR5"
			(at 0 0 270)
			(unlocked yes)
			(layer "F.Fab")
			(hide yes)
			(effects
				(font
					(size 1 1)
					(thickness 0.15)
				)
			)
		)
		(property "Manufacturer" "Intel"
			(at 0 0 270)
			(unlocked yes)
			(layer "F.Fab")
			(hide yes)
			(effects
				(font
					(size 1 1)
					(thickness 0.15)
				)
			)
		)
		(property "Author" "Antmicro"
			(at 0 0 270)
			(unlocked yes)
			(layer "F.Fab")
			(hide yes)
			(effects
				(font
					(size 1 1)
					(thickness 0.15)
				)
			)
		)
		(property "License" "Apache-2.0"
			(at 0 0 270)
			(unlocked yes)
			(layer "F.Fab")
			(hide yes)
			(effects
				(font
					(size 1 1)
					(thickness 0.15)
				)
			)
		)
		(sheetname "/X710-AT2 power/")
		(sheetfile "x710-at2-power.kicad_sch")
		(attr smd)
		(pad "W37" smd circle
			(at 7.75 5.62 270)
			(size 0.5 0.5)
			(layers "F.Cu" "F.Mask" "F.Paste")
			(net 23 "GND")
			(pinfunction "VSSA")
			(pintype "passive")
		)
		(pad "W39" smd circle
			(at 8.75 5.62 270)
			(size 0.5 0.5)
			(layers "F.Cu" "F.Mask" "F.Paste")
			(net 23 "GND")
			(pinfunction "VSSA")
			(pintype "passive")
		)
		(pad "W41" smd circle
			(at 9.75 5.62 270)
			(size 0.5 0.5)
			(layers "F.Cu" "F.Mask" "F.Paste")
			(net 489 "unconnected-(U14D-GPIO_1-PadW41)")
			(pinfunction "GPIO_1")
			(pintype "passive+no_connect")
		)
		(pad "Y2" smd circle
			(at -9.75 6.485 270)
			(size 0.5 0.5)
			(layers "F.Cu" "F.Mask" "F.Paste")
			(net 23 "GND")
			(pinfunction "VSS_S")
			(pintype "power_in")
		)
		(pad "Y4" smd circle
			(at -8.75 6.485 270)
			(size 0.5 0.5)
			(layers "F.Cu" "F.Mask" "F.Paste")
			(net 23 "GND")
			(pinfunction "VSSA")
			(pintype "passive")
		)
		(pad "Y6" smd circle
			(at -7.75 6.485 270)
			(size 0.5 0.5)
			(layers "F.Cu" "F.Mask" "F.Paste")
			(net 23 "GND")
			(pinfunction "VSSA")
			(pintype "passive")
		)
		(pad "Y8" smd circle
			(at -6.75 6.485 270)
			(size 0.5 0.5)
			(layers "F.Cu" "F.Mask" "F.Paste")
			(net 23 "GND")
			(pinfunction "VSSA")
			(pintype "passive")
		)
		(pad "Y10" smd circle
			(at -5.75 6.485 270)
			(size 0.5 0.5)
			(layers "F.Cu" "F.Mask" "F.Paste")
			(net 3 "/X710-AT2 PCIe/RBIAS")
			(pinfunction "RBIAS")
			(pintype "passive")
		)
		(pad "Y12" smd circle
			(at -4.75 6.485 270)
			(size 0.5 0.5)
			(layers "F.Cu" "F.Mask" "F.Paste")
			(net 2 "/X710-AT2 PCIe/RSENSE")
			(pinfunction "RSENSE")
			(pintype "passive")
		)
		(pad "Y14" smd circle
			(at -3.75 6.485 270)
			(size 0.5 0.5)
			(layers "F.Cu" "F.Mask" "F.Paste")
			(net 23 "GND")
			(pinfunction "VSSA")
			(pintype "passive")
		)
		(pad "Y16" smd circle
			(at -2.75 6.485 270)
			(size 0.5 0.5)
			(layers "F.Cu" "F.Mask" "F.Paste")
			(net 91 "/X710-AT2 RSVD/DEBUG_Y16")
			(pinfunction "DEBUG_Y16")
			(pintype "passive")
		)
		(pad "Y18" smd circle
			(at -1.75 6.485 270)
			(size 0.5 0.5)
			(layers "F.Cu" "F.Mask" "F.Paste")
			(net 98 "/X710-AT2 RSVD/RSVDY18_VSS")
			(pinfunction "RSVDY18_VSS")
			(pintype "passive")
		)
		(pad "Y20" smd circle
			(at -0.75 6.485 270)
			(size 0.5 0.5)
			(layers "F.Cu" "F.Mask" "F.Paste")
			(net 89 "/X710-AT2 RSVD/DEBUG_Y20")
			(pinfunction "DEBUG_Y20")
			(pintype "passive")
		)
		(pad "Y22" smd circle
			(at 0.25 6.485 270)
			(size 0.5 0.5)
			(layers "F.Cu" "F.Mask" "F.Paste")
			(net 93 "/X710-AT2 RSVD/RSVDY22_VSS")
			(pinfunction "RSVDY22_VSS")
			(pintype "passive")
		)
		(pad "Y24" smd circle
			(at 1.25 6.485 270)
			(size 0.5 0.5)
			(layers "F.Cu" "F.Mask" "F.Paste")
			(net 92 "/X710-AT2 RSVD/RSVDY24_VSS")
			(pinfunction "RSVDY24_VSS")
			(pintype "passive")
		)
		(pad "Y26" smd circle
			(at 2.25 6.485 270)
			(size 0.5 0.5)
			(layers "F.Cu" "F.Mask" "F.Paste")
			(net 23 "GND")
			(pinfunction "VSSA")
			(pintype "passive")
		)
		(pad "Y28" smd circle
			(at 3.25 6.485 270)
			(size 0.5 0.5)
			(layers "F.Cu" "F.Mask" "F.Paste")
			(net 23 "GND")
			(pinfunction "VSSA")
			(pintype "passive")
		)
		(pad "Y30" smd circle
			(at 4.25 6.485 270)
			(size 0.5 0.5)
			(layers "F.Cu" "F.Mask" "F.Paste")
			(net 544 "unconnected-(U14A-PER_5_P-PadY30)")
			(pinfunction "PER_5_P")
			(pintype "input+no_connect")
		)
		(pad "Y32" smd circle
			(at 5.25 6.485 270)
			(size 0.5 0.5)
			(layers "F.Cu" "F.Mask" "F.Paste")
			(net 23 "GND")
			(pinfunction "VSSA")
			(pintype "passive")
		)
		(pad "Y34" smd circle
			(at 6.25 6.485 270)
			(size 0.5 0.5)
			(layers "F.Cu" "F.Mask" "F.Paste")
			(net 563 "unconnected-(U14A-PER_6_P-PadY34)")
			(pinfunction "PER_6_P")
			(pintype "input+no_connect")
		)
		(pad "Y36" smd circle
			(at 7.25 6.485 270)
			(size 0.5 0.5)
			(layers "F.Cu" "F.Mask" "F.Paste")
			(net 23 "GND")
			(pinfunction "VSSA")
			(pintype "passive")
		)
		(pad "Y38" smd circle
			(at 8.25 6.485 270)
			(size 0.5 0.5)
			(layers "F.Cu" "F.Mask" "F.Paste")
			(net 451 "unconnected-(U14A-PER_7_P-PadY38)")
			(pinfunction "PER_7_P")
			(pintype "input+no_connect")
		)
		(pad "Y40" smd circle
			(at 9.25 6.485 270)
			(size 0.5 0.5)
			(layers "F.Cu" "F.Mask" "F.Paste")
			(net 23 "GND")
			(pinfunction "VSSA")
			(pintype "passive")
		)
		(pad "Y42" smd circle
			(at 10.25 6.485 270)
			(size 0.5 0.5)
			(layers "F.Cu" "F.Mask" "F.Paste")
			(net 65 "/2xRJ45/~{P1_LINK_LESS_THAN_10G}")
			(pinfunction "GPIO_2")
			(pintype "tri_state")
		)
	)
)
